# BASEBOARD_FAB2 (Tioga Pass) — schematic netlist excerpt (pin names and nets, part order shuffled) for the footprints in the layout excerpt that follows; sources: Cadence DE-HDL packaged netlist, KiCad conversion of Wiwynn_Tioga_Pass_MB.brd

R7B7  RES  10.0K 1% EMPTY  pkg 0402  page 116 : A = A_EXTCLKP ; B = GND
C4F10  CAP_A  0.01UF 25V 10% X7R  pkg 0402V  page 43 : A = M_A_VREF ; B = GND

(kicad_pcb
	(version 20260206)
	(generator "pcbnew")
	(generator_version "10.0")
	(general
		(thickness 1.6)
		(legacy_teardrops no)
	)
	(paper "A4")
	(title_block
		(title "Wiwynn_Tioga_Pass_MB.brd")
		(comment 1 "Tioga Pass / footprints 446-447 of 4770")
	)
	(layers
		(0 "F.Cu" signal "TOP")
		(4 "In1.Cu" signal "L2GND")
		(6 "In2.Cu" signal "L3")
		(8 "In3.Cu" signal "L4GND")
		(10 "In4.Cu" signal "L5")
		(12 "In5.Cu" signal "L6GND")
		(14 "In6.Cu" signal "L7VCC")
		(16 "In7.Cu" signal "L8VCC")
		(18 "In8.Cu" signal "L9GND")
		(20 "In9.Cu" signal "L10")
		(22 "In10.Cu" signal "L11GND")
		(24 "In11.Cu" signal "L12")
		(26 "In12.Cu" signal "L13GND")
		(2 "B.Cu" signal "BOTTOM")
		(9 "F.Adhes" user "F.Adhesive")
		(11 "B.Adhes" user "B.Adhesive")
		(13 "F.Paste" user "Package Geometry/Pastemask Top")
		(15 "B.Paste" user "Package Geometry/Pastemask Bottom")
		(5 "F.SilkS" user "Ref Des/Silkscreen Top")
		(7 "B.SilkS" user "Ref Des/Silkscreen Bottom")
		(1 "F.Mask" user "Board Geometry/Soldermask Top")
		(3 "B.Mask" user "Board Geometry/Soldermask Bottom")
		(17 "Dwgs.User" user "User.Drawings")
		(19 "Cmts.User" user "User.Comments")
		(21 "Eco1.User" user "User.Eco1")
		(23 "Eco2.User" user "User.Eco2")
		(25 "Edge.Cuts" user "Board Geometry/Outline")
		(27 "Margin" user)
		(31 "F.CrtYd" user "Package Geometry/Place Bound Top")
		(29 "B.CrtYd" user "Package Geometry/Place Bound Bottom")
		(35 "F.Fab" user "Ref Des/Assembly Top")
		(33 "B.Fab" user "Ref Des/Assembly Bottom")
	)
	(footprint ""
		(layer "F.Cu")
		(at 370.7384 -128.524 -90)
		(property "Reference" "R7B7"
			(at 0 0 270)
			(layer "F.SilkS")
			(hide yes)
			(effects
				(font
					(size 1.27 1.27)
				)
			)
		)
		(property "Value" ""
			(at 0 0 270)
			(layer "F.Fab")
			(effects
				(font
					(size 1.27 1.27)
				)
			)
		)
		(duplicate_pad_numbers_are_jumpers no)
		(fp_poly
			(pts
				(xy -0.2794 -0.1016) (xy 0.2794 -0.1016) (xy 0.2794 0.9906) (xy -0.2794 0.9906)
			)
			(stroke
				(width 0)
				(type default)
			)
			(fill no)
			(layer "F.CrtYd")
		)
		(fp_line
			(start -0.2794 0.9906)
			(end 0.2794 0.9906)
			(stroke
				(width 0.1)
				(type default)
			)
			(layer "F.Fab")
		)
		(fp_line
			(start 0.2794 0.9906)
			(end 0.2794 -0.1016)
			(stroke
				(width 0.1)
				(type default)
			)
			(layer "F.Fab")
		)
		(fp_line
			(start -0.2794 -0.1016)
			(end -0.2794 0.9906)
			(stroke
				(width 0.1)
				(type default)
			)
			(layer "F.Fab")
		)
		(fp_line
			(start 0.2794 -0.1016)
			(end -0.2794 -0.1016)
			(stroke
				(width 0.1)
				(type default)
			)
			(layer "F.Fab")
		)
		(pad "1" smd rect
			(at 0 0 270)
			(size 0.508 0.508)
			(layers "F.Cu" "F.Mask" "F.Paste")
			(net "A_EXTCLKP")
		)
		(pad "2" smd rect
			(at 0 0.889 270)
			(size 0.508 0.508)
			(layers "F.Cu" "F.Mask" "F.Paste")
			(net "GND")
		)
		(zone
			(layer "F.Cu")
			(hatch none 0.5)
			(connect_pads
				(clearance 0)
			)
			(min_thickness 0.25)
			(keepout
				(tracks not_allowed)
				(vias allowed)
				(pads allowed)
				(copperpour not_allowed)
				(footprints allowed)
			)
			(placement
				(enabled no)
				(sheetname "")
			)
			(fill
				(thermal_gap 0.5)
				(thermal_bridge_width 0.5)
				(island_removal_mode 0)
			)
			(polygon
				(pts
					(xy 370.1034 -128.778) (xy 370.1034 -128.27) (xy 370.4844 -128.27) (xy 370.4844 -128.778)
				)
			)
		)
		(zone
			(layer "F.Cu")
			(hatch none 0.5)
			(connect_pads
				(clearance 0)
			)
			(min_thickness 0.25)
			(keepout
				(tracks allowed)
				(vias not_allowed)
				(pads allowed)
				(copperpour not_allowed)
				(footprints allowed)
			)
			(placement
				(enabled no)
				(sheetname "")
			)
			(fill
				(thermal_gap 0.5)
				(thermal_bridge_width 0.5)
				(island_removal_mode 0)
			)
			(polygon
				(pts
					(xy 370.4844 -128.778) (xy 370.4844 -128.27) (xy 370.1034 -128.27) (xy 370.1034 -128.778)
				)
			)
		)
	)
	(footprint ""
		(layer "F.Cu")
		(at 195.58 -22.606 90)
		(property "Reference" "C4F10"
			(at 0 0 90)
			(layer "F.SilkS")
			(hide yes)
			(effects
				(font
					(size 1.27 1.27)
				)
			)
		)
		(property "Value" ""
			(at 0 0 90)
			(layer "F.Fab")
			(effects
				(font
					(size 1.27 1.27)
				)
			)
		)
		(duplicate_pad_numbers_are_jumpers no)
		(fp_poly
			(pts
				(xy 0.3048 -0.1016) (xy 0.3048 0.9906) (xy -0.3048 0.9906) (xy -0.3048 -0.1016)
			)
			(stroke
				(width 0)
				(type default)
			)
			(fill no)
			(layer "F.CrtYd")
		)
		(fp_line
			(start 0.3048 -0.1016)
			(end -0.3048 -0.1016)
			(stroke
				(width 0.1)
				(type default)
			)
			(layer "F.Fab")
		)
		(fp_line
			(start -0.3048 -0.1016)
			(end -0.3048 0.9906)
			(stroke
				(width 0.1)
				(type default)
			)
			(layer "F.Fab")
		)
		(fp_line
			(start 0.3048 0.9906)
			(end 0.3048 -0.1016)
			(stroke
				(width 0.1)
				(type default)
			)
			(layer "F.Fab")
		)
		(fp_line
			(start -0.3048 0.9906)
			(end 0.3048 0.9906)
			(stroke
				(width 0.1)
				(type default)
			)
			(layer "F.Fab")
		)
		(pad "1" smd rect
			(at 0 0 90)
			(size 0.508 0.508)
			(layers "F.Cu" "F.Mask" "F.Paste")
			(net "M_A_VREF")
		)
		(pad "2" smd rect
			(at 0 0.889 90)
			(size 0.508 0.508)
			(layers "F.Cu" "F.Mask" "F.Paste")
			(net "GND")
		)
		(zone
			(layer "F.Cu")
			(hatch none 0.5)
			(connect_pads
				(clearance 0)
			)
			(min_thickness 0.25)
			(keepout
				(tracks allowed)
				(vias not_allowed)
				(pads allowed)
				(copperpour not_allowed)
				(footprints allowed)
			)
			(placement
				(enabled no)
				(sheetname "")
			)
			(fill
				(thermal_gap 0.5)
				(thermal_bridge_width 0.5)
				(island_removal_mode 0)
			)
			(polygon
				(pts
					(xy 195.834 -22.352) (xy 195.834 -22.86) (xy 196.215 -22.86) (xy 196.215 -22.352)
				)
			)
		)
		(zone
			(layer "F.Cu")
			(hatch none 0.5)
			(connect_pads
				(clearance 0)
			)
			(min_thickness 0.25)
			(keepout
				(tracks not_allowed)
				(vias allowed)
				(pads allowed)
				(copperpour not_allowed)
				(footprints allowed)
			)
			(placement
				(enabled no)
				(sheetname "")
			)
			(fill
				(thermal_gap 0.5)
				(thermal_bridge_width 0.5)
				(island_removal_mode 0)
			)
			(polygon
				(pts
					(xy 196.215 -22.352) (xy 196.215 -22.86) (xy 195.834 -22.86) (xy 195.834 -22.352)
				)
			)
		)
	)
)
